# S9S_MB_2U (Grand Teton) — schematic netlist excerpt (pin names and nets, part order shuffled) for the footprints in the layout excerpt that follows; sources: Cadence DE-HDL packaged netlist, KiCad conversion of 03242023_DA0F0TMBIJ0_F0T_Motherboard_J_brd_V01_OCP.brd

PL9  Q_INDUCTOR4P_14  150NH IND  pkg L_TLM117513Q-151QL_11X7-5XA  page 269
  \1\  = SW_PVCCIN_CPU0_SW6
  \2\  = IND_P0_CPL6
  \3\  = IND_P0_CPL1
  \4\  = PVCCIN_CPU0

PC1173_P0_3  Q_CAP  3300PF 50V 10% X7R  pkg 0402  page 272 : A = SW_P12V_PVCCFA_EHV_FIVRA_CPU0_R ; B = GND

(kicad_pcb
	(version 20260206)
	(generator "pcbnew")
	(generator_version "10.0")
	(general
		(thickness 1.6)
		(legacy_teardrops no)
	)
	(paper "A4")
	(title_block
		(title "03242023_DA0F0TMBIJ0_F0T_Motherboard_J_brd_V01_OCP.brd")
		(comment 1 "Grand Teton / footprints 229-230 of 6105")
	)
	(layers
		(0 "F.Cu" signal "TOP")
		(4 "In1.Cu" signal "GND")
		(6 "In2.Cu" signal "IN1")
		(8 "In3.Cu" signal "GND1")
		(10 "In4.Cu" signal "IN2")
		(12 "In5.Cu" signal "GND2")
		(14 "In6.Cu" signal "IN3")
		(16 "In7.Cu" signal "GND3")
		(18 "In8.Cu" signal "VCC")
		(20 "In9.Cu" signal "VCC1")
		(22 "In10.Cu" signal "GND4")
		(24 "In11.Cu" signal "IN4")
		(26 "In12.Cu" signal "GND5")
		(28 "In13.Cu" signal "IN5")
		(30 "In14.Cu" signal "GND6")
		(32 "In15.Cu" signal "IN6")
		(34 "In16.Cu" signal "GND7")
		(2 "B.Cu" signal "BOTTOM")
		(9 "F.Adhes" user "F.Adhesive")
		(11 "B.Adhes" user "B.Adhesive")
		(13 "F.Paste" user "Package Geometry/Pastemask Top")
		(15 "B.Paste" user "Package Geometry/Pastemask Bottom")
		(5 "F.SilkS" user "Ref Des/Silkscreen Top")
		(7 "B.SilkS" user "Ref Des/Silkscreen Bottom")
		(1 "F.Mask" user "Board Geometry/Soldermask Top")
		(3 "B.Mask" user "Board Geometry/Soldermask Bottom")
		(17 "Dwgs.User" user "User.Drawings")
		(19 "Cmts.User" user "User.Comments")
		(21 "Eco1.User" user "User.Eco1")
		(23 "Eco2.User" user "User.Eco2")
		(25 "Edge.Cuts" user "Board Geometry/Outline")
		(27 "Margin" user)
		(31 "F.CrtYd" user "Package Geometry/Place Bound Top")
		(29 "B.CrtYd" user "Package Geometry/Place Bound Bottom")
		(35 "F.Fab" user "Ref Des/Assembly Top")
		(33 "B.Fab" user "Ref Des/Assembly Bottom")
	)
	(footprint ""
		(layer "F.Cu")
		(at 336.750914 -327.768204)
		(property "Reference" "PL9"
			(at -6.423914 4.195826 0)
			(unlocked yes)
			(layer "F.SilkS")
			(effects
				(font
					(size 0.7874 0.5842)
					(thickness 0.1524)
				)
				(justify left)
			)
		)
		(property "Value" ""
			(at 0 0 0)
			(layer "F.Fab")
			(effects
				(font
					(size 1.27 1.27)
				)
			)
		)
		(duplicate_pad_numbers_are_jumpers no)
		(fp_line
			(start -3.750056 -5.500116)
			(end -2.393442 -5.500116)
			(stroke
				(width 0.1524)
				(type default)
			)
			(layer "F.SilkS")
		)
		(fp_line
			(start -3.750056 5.500116)
			(end -3.750056 -5.500116)
			(stroke
				(width 0.1524)
				(type default)
			)
			(layer "F.SilkS")
		)
		(fp_line
			(start -2.393442 5.500116)
			(end -3.750056 5.500116)
			(stroke
				(width 0.1524)
				(type default)
			)
			(layer "F.SilkS")
		)
		(fp_line
			(start 2.393442 5.500116)
			(end 3.750056 5.500116)
			(stroke
				(width 0.1524)
				(type default)
			)
			(layer "F.SilkS")
		)
		(fp_line
			(start 3.750056 -5.500116)
			(end 2.393442 -5.500116)
			(stroke
				(width 0.1524)
				(type default)
			)
			(layer "F.SilkS")
		)
		(fp_line
			(start 3.750056 -1.507744)
			(end 3.750056 -5.500116)
			(stroke
				(width 0.1524)
				(type default)
			)
			(layer "F.SilkS")
		)
		(fp_line
			(start 3.750056 5.500116)
			(end 3.750056 -0.364744)
			(stroke
				(width 0.1524)
				(type default)
			)
			(layer "F.SilkS")
		)
		(fp_poly
			(pts
				(xy -3.125978 -6.963664) (xy -2.766822 -5.885942) (xy -3.844544 -6.245352)
			)
			(stroke
				(width 0)
				(type default)
			)
			(fill yes)
			(layer "F.SilkS")
		)
		(fp_line
			(start -3.750056 -5.500116)
			(end -3.750056 5.500116)
			(stroke
				(width 0.1)
				(type default)
			)
			(layer "F.Fab")
		)
		(fp_line
			(start -3.750056 5.500116)
			(end 3.750056 5.500116)
			(stroke
				(width 0.1)
				(type default)
			)
			(layer "F.Fab")
		)
		(fp_line
			(start 3.750056 -5.500116)
			(end -3.750056 -5.500116)
			(stroke
				(width 0.1)
				(type default)
			)
			(layer "F.Fab")
		)
		(fp_line
			(start 3.750056 5.500116)
			(end 3.750056 -5.500116)
			(stroke
				(width 0.1)
				(type default)
			)
			(layer "F.Fab")
		)
		(fp_poly
			(pts
				(xy -4.9276 -4.757928) (xy -4.9276 -3.741928) (xy -3.9116 -4.249928)
			)
			(stroke
				(width 0)
				(type default)
			)
			(fill yes)
			(layer "F.Fab")
		)
		(pad "1" smd rect
			(at 0 -4.249928 270)
			(size 2.413 4.5212)
			(layers "F.Cu" "F.Mask" "F.Paste")
			(net "SW_PVCCIN_CPU0_SW6")
		)
		(pad "2" smd rect
			(at 0 -1.175004 270)
			(size 1.3716 4.5212)
			(layers "F.Cu" "F.Mask" "F.Paste")
			(net "IND_P0_CPL6")
		)
		(pad "3" smd rect
			(at 0 1.175004 270)
			(size 1.3716 4.5212)
			(layers "F.Cu" "F.Mask" "F.Paste")
			(net "IND_P0_CPL1")
		)
		(pad "4" smd rect
			(at 0 4.249928 270)
			(size 2.413 4.5212)
			(layers "F.Cu" "F.Mask" "F.Paste")
			(net "PVCCIN_CPU0")
		)
	)
	(footprint ""
		(layer "F.Cu")
		(at 430.573688 -362.18368 -90)
		(property "Reference" "PC1173_P0_3"
			(at 0 0 270)
			(layer "F.SilkS")
			(hide yes)
			(effects
				(font
					(size 1.27 1.27)
				)
			)
		)
		(property "Value" ""
			(at 0 0 270)
			(layer "F.Fab")
			(effects
				(font
					(size 1.27 1.27)
				)
			)
		)
		(duplicate_pad_numbers_are_jumpers no)
		(fp_line
			(start -0.7874 0.4064)
			(end -0.7874 -0.4064)
			(stroke
				(width 0.1524)
				(type default)
			)
			(layer "F.SilkS")
		)
		(fp_line
			(start 0.7874 0.4064)
			(end -0.7874 0.4064)
			(stroke
				(width 0.1524)
				(type default)
			)
			(layer "F.SilkS")
		)
		(fp_line
			(start -0.7874 -0.4064)
			(end 0.7874 -0.4064)
			(stroke
				(width 0.1524)
				(type default)
			)
			(layer "F.SilkS")
		)
		(fp_line
			(start 0.7874 -0.4064)
			(end 0.7874 0.4064)
			(stroke
				(width 0.1524)
				(type default)
			)
			(layer "F.SilkS")
		)
		(fp_line
			(start -0.67945 0.3048)
			(end -0.67945 -0.305054)
			(stroke
				(width 0.1)
				(type default)
			)
			(layer "F.Fab")
		)
		(fp_line
			(start -0.12065 0.3048)
			(end -0.67945 0.3048)
			(stroke
				(width 0.1)
				(type default)
			)
			(layer "F.Fab")
		)
		(fp_line
			(start 0.120396 0.3048)
			(end 0.120396 0.2794)
			(stroke
				(width 0.1)
				(type default)
			)
			(layer "F.Fab")
		)
		(fp_line
			(start 0.67945 0.3048)
			(end 0.120396 0.3048)
			(stroke
				(width 0.1)
				(type default)
			)
			(layer "F.Fab")
		)
		(fp_line
			(start -0.12065 0.2794)
			(end -0.12065 0.3048)
			(stroke
				(width 0.1)
				(type default)
			)
			(layer "F.Fab")
		)
		(fp_line
			(start 0.120396 0.2794)
			(end -0.12065 0.2794)
			(stroke
				(width 0.1)
				(type default)
			)
			(layer "F.Fab")
		)
		(fp_line
			(start -0.12065 -0.2794)
			(end 0.12065 -0.2794)
			(stroke
				(width 0.1)
				(type default)
			)
			(layer "F.Fab")
		)
		(fp_line
			(start 0.12065 -0.2794)
			(end 0.12065 -0.3048)
			(stroke
				(width 0.1)
				(type default)
			)
			(layer "F.Fab")
		)
		(fp_line
			(start 0.12065 -0.3048)
			(end 0.67945 -0.3048)
			(stroke
				(width 0.1)
				(type default)
			)
			(layer "F.Fab")
		)
		(fp_line
			(start 0.67945 -0.3048)
			(end 0.67945 0.3048)
			(stroke
				(width 0.1)
				(type default)
			)
			(layer "F.Fab")
		)
		(fp_line
			(start -0.67945 -0.305054)
			(end -0.12065 -0.305054)
			(stroke
				(width 0.1)
				(type default)
			)
			(layer "F.Fab")
		)
		(fp_line
			(start -0.12065 -0.305054)
			(end -0.12065 -0.2794)
			(stroke
				(width 0.1)
				(type default)
			)
			(layer "F.Fab")
		)
		(pad "1" smd circle
			(at -0.40005 0 270)
			(size 0 0)
			(layers "F.Cu" "F.Mask" "F.Paste")
			(net "SW_P12V_PVCCFA_EHV_FIVRA_CPU0_R")
		)
		(pad "2" smd circle
			(at 0.40005 0 270)
			(size 0 0)
			(layers "F.Cu" "F.Mask" "F.Paste")
			(net "GND")
		)
	)
)
